(kicad_pcb
	(version 20260206)
	(generator "pcbnew")
	(generator_version "10.0")
	(general
		(thickness 1.6)
		(legacy_teardrops no)
	)
	(paper "A4")
	(title_block
		(title "9054_F0T_PDB_BD_GPU_F_V04_1213_1550_OCP.brd")
		(comment 1 "Grand Teton / footprints 124-130 of 608")
	)
	(layers
		(0 "F.Cu" signal "TOP")
		(4 "In1.Cu" signal "GND")
		(6 "In2.Cu" signal "IN1")
		(8 "In3.Cu" signal "GND1")
		(10 "In4.Cu" signal "VCC")
		(12 "In5.Cu" signal "VCC1")
		(14 "In6.Cu" signal "GND2")
		(16 "In7.Cu" signal "IN2")
		(18 "In8.Cu" signal "GND3")
		(2 "B.Cu" signal "BOTTOM")
		(9 "F.Adhes" user "F.Adhesive")
		(11 "B.Adhes" user "B.Adhesive")
		(13 "F.Paste" user "Package Geometry/Pastemask Top")
		(15 "B.Paste" user "Package Geometry/Pastemask Bottom")
		(5 "F.SilkS" user "Ref Des/Silkscreen Top")
		(7 "B.SilkS" user "Ref Des/Silkscreen Bottom")
		(1 "F.Mask" user "Board Geometry/Soldermask Top")
		(3 "B.Mask" user "Board Geometry/Soldermask Bottom")
		(17 "Dwgs.User" user "User.Drawings")
		(19 "Cmts.User" user "User.Comments")
		(21 "Eco1.User" user "User.Eco1")
		(23 "Eco2.User" user "User.Eco2")
		(25 "Edge.Cuts" user "Board Geometry/Outline")
		(27 "Margin" user)
		(31 "F.CrtYd" user "Package Geometry/Place Bound Top")
		(29 "B.CrtYd" user "Package Geometry/Place Bound Bottom")
		(35 "F.Fab" user "Ref Des/Assembly Top")
		(33 "B.Fab" user "Ref Des/Assembly Bottom")
	)
	(footprint ""
		(layer "F.Cu")
		(at 47.513494 -23.114)
		(property "Reference" "PR106"
			(at -7.991094 0.28067 0)
			(unlocked yes)
			(layer "F.SilkS")
			(effects
				(font
					(size 0.7874 0.5842)
					(thickness 0.1524)
				)
				(justify left)
			)
		)
		(property "Value" ""
			(at 0 0 0)
			(layer "F.Fab")
			(effects
				(font
					(size 1.27 1.27)
				)
			)
		)
		(duplicate_pad_numbers_are_jumpers no)
		(fp_line
			(start -3.62712 -1.8796)
			(end -3.62712 1.8796)
			(stroke
				(width 0.1524)
				(type default)
			)
			(layer "F.SilkS")
		)
		(fp_line
			(start -3.62712 1.8796)
			(end 3.62712 1.8796)
			(stroke
				(width 0.1524)
				(type default)
			)
			(layer "F.SilkS")
		)
		(fp_line
			(start 3.62712 -1.8796)
			(end -3.62712 -1.8796)
			(stroke
				(width 0.1524)
				(type default)
			)
			(layer "F.SilkS")
		)
		(fp_line
			(start 3.62712 1.8796)
			(end 3.62712 -1.8796)
			(stroke
				(width 0.1524)
				(type default)
			)
			(layer "F.SilkS")
		)
		(fp_line
			(start -3.299968 -1.700022)
			(end -3.299968 1.700022)
			(stroke
				(width 0.1)
				(type default)
			)
			(layer "F.Fab")
		)
		(fp_line
			(start -3.299968 1.700022)
			(end 3.299968 1.700022)
			(stroke
				(width 0.1)
				(type default)
			)
			(layer "F.Fab")
		)
		(fp_line
			(start 3.299968 -1.700022)
			(end -3.299968 -1.700022)
			(stroke
				(width 0.1)
				(type default)
			)
			(layer "F.Fab")
		)
		(fp_line
			(start 3.299968 1.700022)
			(end 3.299968 -1.700022)
			(stroke
				(width 0.1)
				(type default)
			)
			(layer "F.Fab")
		)
		(pad "1" smd rect
			(at -2.70002 0)
			(size 1.6002 3.5052)
			(layers "F.Cu" "F.Mask" "F.Paste")
			(net "P52V_HS2_EN_DISCHARGE_VBE_R")
		)
		(pad "2" smd rect
			(at 2.70002 0)
			(size 1.6002 3.5052)
			(layers "F.Cu" "F.Mask" "F.Paste")
			(net "GND")
		)
	)
	(footprint ""
		(layer "F.Cu")
		(at 436.245 -30.353 180)
		(property "Reference" "R15"
			(at 0 0 180)
			(layer "F.SilkS")
			(hide yes)
			(effects
				(font
					(size 1.27 1.27)
				)
			)
		)
		(property "Value" ""
			(at 0 0 180)
			(layer "F.Fab")
			(effects
				(font
					(size 1.27 1.27)
				)
			)
		)
		(duplicate_pad_numbers_are_jumpers no)
		(fp_line
			(start 0.7874 0.4064)
			(end -0.7874 0.4064)
			(stroke
				(width 0.1524)
				(type default)
			)
			(layer "F.SilkS")
		)
		(fp_line
			(start 0.7874 -0.4064)
			(end 0.7874 0.4064)
			(stroke
				(width 0.1524)
				(type default)
			)
			(layer "F.SilkS")
		)
		(fp_line
			(start -0.7874 0.4064)
			(end -0.7874 -0.4064)
			(stroke
				(width 0.1524)
				(type default)
			)
			(layer "F.SilkS")
		)
		(fp_line
			(start -0.7874 -0.4064)
			(end 0.7874 -0.4064)
			(stroke
				(width 0.1524)
				(type default)
			)
			(layer "F.SilkS")
		)
		(fp_line
			(start 0.67945 0.3048)
			(end 0.120396 0.3048)
			(stroke
				(width 0.1)
				(type default)
			)
			(layer "F.Fab")
		)
		(fp_line
			(start 0.67945 -0.3048)
			(end 0.67945 0.3048)
			(stroke
				(width 0.1)
				(type default)
			)
			(layer "F.Fab")
		)
		(fp_line
			(start 0.12065 -0.2794)
			(end 0.12065 -0.3048)
			(stroke
				(width 0.1)
				(type default)
			)
			(layer "F.Fab")
		)
		(fp_line
			(start 0.12065 -0.3048)
			(end 0.67945 -0.3048)
			(stroke
				(width 0.1)
				(type default)
			)
			(layer "F.Fab")
		)
		(fp_line
			(start 0.120396 0.3048)
			(end 0.120396 0.2794)
			(stroke
				(width 0.1)
				(type default)
			)
			(layer "F.Fab")
		)
		(fp_line
			(start 0.120396 0.2794)
			(end -0.12065 0.2794)
			(stroke
				(width 0.1)
				(type default)
			)
			(layer "F.Fab")
		)
		(fp_line
			(start -0.12065 0.3048)
			(end -0.67945 0.3048)
			(stroke
				(width 0.1)
				(type default)
			)
			(layer "F.Fab")
		)
		(fp_line
			(start -0.12065 0.2794)
			(end -0.12065 0.3048)
			(stroke
				(width 0.1)
				(type default)
			)
			(layer "F.Fab")
		)
		(fp_line
			(start -0.12065 -0.2794)
			(end 0.12065 -0.2794)
			(stroke
				(width 0.1)
				(type default)
			)
			(layer "F.Fab")
		)
		(fp_line
			(start -0.12065 -0.305054)
			(end -0.12065 -0.2794)
			(stroke
				(width 0.1)
				(type default)
			)
			(layer "F.Fab")
		)
		(fp_line
			(start -0.67945 0.3048)
			(end -0.67945 -0.305054)
			(stroke
				(width 0.1)
				(type default)
			)
			(layer "F.Fab")
		)
		(fp_line
			(start -0.67945 -0.305054)
			(end -0.12065 -0.305054)
			(stroke
				(width 0.1)
				(type default)
			)
			(layer "F.Fab")
		)
		(pad "1" smd circle
			(at -0.40005 0 180)
			(size 0 0)
			(layers "F.Cu" "F.Mask" "F.Paste")
			(net "PU_9543_0_FAN")
		)
		(pad "2" smd circle
			(at 0.40005 0 180)
			(size 0 0)
			(layers "F.Cu" "F.Mask" "F.Paste")
			(net "P3V3_AUX")
		)
	)
	(footprint ""
		(layer "F.Cu")
		(at 168.956736 -63.881 180)
		(property "Reference" "PR7031"
			(at 0 0 180)
			(layer "F.SilkS")
			(hide yes)
			(effects
				(font
					(size 1.27 1.27)
				)
			)
		)
		(property "Value" ""
			(at 0 0 180)
			(layer "F.Fab")
			(effects
				(font
					(size 1.27 1.27)
				)
			)
		)
		(duplicate_pad_numbers_are_jumpers no)
		(fp_line
			(start 0.7874 0.4064)
			(end -0.7874 0.4064)
			(stroke
				(width 0.1524)
				(type default)
			)
			(layer "F.SilkS")
		)
		(fp_line
			(start 0.7874 -0.4064)
			(end 0.7874 0.4064)
			(stroke
				(width 0.1524)
				(type default)
			)
			(layer "F.SilkS")
		)
		(fp_line
			(start -0.7874 0.4064)
			(end -0.7874 -0.4064)
			(stroke
				(width 0.1524)
				(type default)
			)
			(layer "F.SilkS")
		)
		(fp_line
			(start -0.7874 -0.4064)
			(end 0.7874 -0.4064)
			(stroke
				(width 0.1524)
				(type default)
			)
			(layer "F.SilkS")
		)
		(fp_line
			(start 0.67945 0.3048)
			(end 0.120396 0.3048)
			(stroke
				(width 0.1)
				(type default)
			)
			(layer "F.Fab")
		)
		(fp_line
			(start 0.67945 -0.3048)
			(end 0.67945 0.3048)
			(stroke
				(width 0.1)
				(type default)
			)
			(layer "F.Fab")
		)
		(fp_line
			(start 0.12065 -0.2794)
			(end 0.12065 -0.3048)
			(stroke
				(width 0.1)
				(type default)
			)
			(layer "F.Fab")
		)
		(fp_line
			(start 0.12065 -0.3048)
			(end 0.67945 -0.3048)
			(stroke
				(width 0.1)
				(type default)
			)
			(layer "F.Fab")
		)
		(fp_line
			(start 0.120396 0.3048)
			(end 0.120396 0.2794)
			(stroke
				(width 0.1)
				(type default)
			)
			(layer "F.Fab")
		)
		(fp_line
			(start 0.120396 0.2794)
			(end -0.12065 0.2794)
			(stroke
				(width 0.1)
				(type default)
			)
			(layer "F.Fab")
		)
		(fp_line
			(start -0.12065 0.3048)
			(end -0.67945 0.3048)
			(stroke
				(width 0.1)
				(type default)
			)
			(layer "F.Fab")
		)
		(fp_line
			(start -0.12065 0.2794)
			(end -0.12065 0.3048)
			(stroke
				(width 0.1)
				(type default)
			)
			(layer "F.Fab")
		)
		(fp_line
			(start -0.12065 -0.2794)
			(end 0.12065 -0.2794)
			(stroke
				(width 0.1)
				(type default)
			)
			(layer "F.Fab")
		)
		(fp_line
			(start -0.12065 -0.305054)
			(end -0.12065 -0.2794)
			(stroke
				(width 0.1)
				(type default)
			)
			(layer "F.Fab")
		)
		(fp_line
			(start -0.67945 0.3048)
			(end -0.67945 -0.305054)
			(stroke
				(width 0.1)
				(type default)
			)
			(layer "F.Fab")
		)
		(fp_line
			(start -0.67945 -0.305054)
			(end -0.12065 -0.305054)
			(stroke
				(width 0.1)
				(type default)
			)
			(layer "F.Fab")
		)
		(pad "1" smd circle
			(at -0.40005 0 180)
			(size 0 0)
			(layers "F.Cu" "F.Mask" "F.Paste")
			(net "P52V_HS2_ESTART_R")
		)
		(pad "2" smd circle
			(at 0.40005 0 180)
			(size 0 0)
			(layers "F.Cu" "F.Mask" "F.Paste")
			(net "P52V_HS2_ESTART")
		)
	)
	(footprint ""
		(layer "F.Cu")
		(at 172.4914 -75.819 180)
		(property "Reference" "R5888"
			(at 0 0 180)
			(layer "F.SilkS")
			(hide yes)
			(effects
				(font
					(size 1.27 1.27)
				)
			)
		)
		(property "Value" ""
			(at 0 0 180)
			(layer "F.Fab")
			(effects
				(font
					(size 1.27 1.27)
				)
			)
		)
		(duplicate_pad_numbers_are_jumpers no)
		(fp_line
			(start 0.7874 0.4064)
			(end -0.7874 0.4064)
			(stroke
				(width 0.1524)
				(type default)
			)
			(layer "F.SilkS")
		)
		(fp_line
			(start 0.7874 -0.4064)
			(end 0.7874 0.4064)
			(stroke
				(width 0.1524)
				(type default)
			)
			(layer "F.SilkS")
		)
		(fp_line
			(start -0.7874 0.4064)
			(end -0.7874 -0.4064)
			(stroke
				(width 0.1524)
				(type default)
			)
			(layer "F.SilkS")
		)
		(fp_line
			(start -0.7874 -0.4064)
			(end 0.7874 -0.4064)
			(stroke
				(width 0.1524)
				(type default)
			)
			(layer "F.SilkS")
		)
		(fp_line
			(start 0.67945 0.3048)
			(end 0.120396 0.3048)
			(stroke
				(width 0.1)
				(type default)
			)
			(layer "F.Fab")
		)
		(fp_line
			(start 0.67945 -0.3048)
			(end 0.67945 0.3048)
			(stroke
				(width 0.1)
				(type default)
			)
			(layer "F.Fab")
		)
		(fp_line
			(start 0.12065 -0.2794)
			(end 0.12065 -0.3048)
			(stroke
				(width 0.1)
				(type default)
			)
			(layer "F.Fab")
		)
		(fp_line
			(start 0.12065 -0.3048)
			(end 0.67945 -0.3048)
			(stroke
				(width 0.1)
				(type default)
			)
			(layer "F.Fab")
		)
		(fp_line
			(start 0.120396 0.3048)
			(end 0.120396 0.2794)
			(stroke
				(width 0.1)
				(type default)
			)
			(layer "F.Fab")
		)
		(fp_line
			(start 0.120396 0.2794)
			(end -0.12065 0.2794)
			(stroke
				(width 0.1)
				(type default)
			)
			(layer "F.Fab")
		)
		(fp_line
			(start -0.12065 0.3048)
			(end -0.67945 0.3048)
			(stroke
				(width 0.1)
				(type default)
			)
			(layer "F.Fab")
		)
		(fp_line
			(start -0.12065 0.2794)
			(end -0.12065 0.3048)
			(stroke
				(width 0.1)
				(type default)
			)
			(layer "F.Fab")
		)
		(fp_line
			(start -0.12065 -0.2794)
			(end 0.12065 -0.2794)
			(stroke
				(width 0.1)
				(type default)
			)
			(layer "F.Fab")
		)
		(fp_line
			(start -0.12065 -0.305054)
			(end -0.12065 -0.2794)
			(stroke
				(width 0.1)
				(type default)
			)
			(layer "F.Fab")
		)
		(fp_line
			(start -0.67945 0.3048)
			(end -0.67945 -0.305054)
			(stroke
				(width 0.1)
				(type default)
			)
			(layer "F.Fab")
		)
		(fp_line
			(start -0.67945 -0.305054)
			(end -0.12065 -0.305054)
			(stroke
				(width 0.1)
				(type default)
			)
			(layer "F.Fab")
		)
		(pad "1" smd circle
			(at -0.40005 0 180)
			(size 0 0)
			(layers "F.Cu" "F.Mask" "F.Paste")
			(net "P52V_HS2_GPO2")
		)
		(pad "2" smd circle
			(at 0.40005 0 180)
			(size 0 0)
			(layers "F.Cu" "F.Mask" "F.Paste")
			(net "P52V_HS2_FLT")
		)
	)
	(footprint ""
		(layer "F.Cu")
		(at 414.49244 -25.66162)
		(property "Reference" "C98"
			(at 0 0 0)
			(layer "F.SilkS")
			(hide yes)
			(effects
				(font
					(size 1.27 1.27)
				)
			)
		)
		(property "Value" ""
			(at 0 0 0)
			(layer "F.Fab")
			(effects
				(font
					(size 1.27 1.27)
				)
			)
		)
		(duplicate_pad_numbers_are_jumpers no)
		(fp_line
			(start -1.2954 -0.5842)
			(end 1.2954 -0.5842)
			(stroke
				(width 0.1524)
				(type default)
			)
			(layer "F.SilkS")
		)
		(fp_line
			(start -1.2954 0.5842)
			(end -1.2954 -0.5842)
			(stroke
				(width 0.1524)
				(type default)
			)
			(layer "F.SilkS")
		)
		(fp_line
			(start 1.2954 -0.5842)
			(end 1.2954 0.5842)
			(stroke
				(width 0.1524)
				(type default)
			)
			(layer "F.SilkS")
		)
		(fp_line
			(start 1.2954 0.5842)
			(end -1.2954 0.5842)
			(stroke
				(width 0.1524)
				(type default)
			)
			(layer "F.SilkS")
		)
		(fp_line
			(start -1.1938 -0.4064)
			(end -0.8636 -0.4064)
			(stroke
				(width 0.1)
				(type default)
			)
			(layer "F.Fab")
		)
		(fp_line
			(start -1.1938 0.4064)
			(end -1.1938 -0.4064)
			(stroke
				(width 0.1)
				(type default)
			)
			(layer "F.Fab")
		)
		(fp_line
			(start -0.8636 -0.4572)
			(end 0.8636 -0.4572)
			(stroke
				(width 0.1)
				(type default)
			)
			(layer "F.Fab")
		)
		(fp_line
			(start -0.8636 -0.4064)
			(end -0.8636 -0.4572)
			(stroke
				(width 0.1)
				(type default)
			)
			(layer "F.Fab")
		)
		(fp_line
			(start -0.8636 0.4064)
			(end -1.1938 0.4064)
			(stroke
				(width 0.1)
				(type default)
			)
			(layer "F.Fab")
		)
		(fp_line
			(start -0.8636 0.4572)
			(end -0.8636 0.4064)
			(stroke
				(width 0.1)
				(type default)
			)
			(layer "F.Fab")
		)
		(fp_line
			(start 0.8636 -0.4572)
			(end 0.8636 -0.4064)
			(stroke
				(width 0.1)
				(type default)
			)
			(layer "F.Fab")
		)
		(fp_line
			(start 0.8636 -0.4064)
			(end 1.1938 -0.4064)
			(stroke
				(width 0.1)
				(type default)
			)
			(layer "F.Fab")
		)
		(fp_line
			(start 0.8636 0.4064)
			(end 0.8636 0.4572)
			(stroke
				(width 0.1)
				(type default)
			)
			(layer "F.Fab")
		)
		(fp_line
			(start 0.8636 0.4572)
			(end -0.8636 0.4572)
			(stroke
				(width 0.1)
				(type default)
			)
			(layer "F.Fab")
		)
		(fp_line
			(start 1.1938 -0.4064)
			(end 1.1938 0.4064)
			(stroke
				(width 0.1)
				(type default)
			)
			(layer "F.Fab")
		)
		(fp_line
			(start 1.1938 0.4064)
			(end 0.8636 0.4064)
			(stroke
				(width 0.1)
				(type default)
			)
			(layer "F.Fab")
		)
		(pad "1" smd rect
			(at -0.7366 0 270)
			(size 0.7112 0.8128)
			(layers "F.Cu" "F.Mask" "F.Paste")
			(net "GND")
		)
		(pad "2" smd rect
			(at 0.7366 0 270)
			(size 0.7112 0.8128)
			(layers "F.Cu" "F.Mask" "F.Paste")
			(net "P12V_LED_PD")
		)
	)
	(footprint ""
		(layer "F.Cu")
		(at 71.000112 -13.499592 180)
		(property "Reference" "H4"
			(at 0.769112 10.476738 0)
			(unlocked yes)
			(layer "F.SilkS")
			(effects
				(font
					(size 0.7874 0.5842)
					(thickness 0.1524)
				)
				(justify left)
			)
		)
		(property "Value" ""
			(at 0 0 180)
			(layer "F.Fab")
			(effects
				(font
					(size 1.27 1.27)
				)
			)
		)
		(duplicate_pad_numbers_are_jumpers no)
		(pad "1" thru_hole oval
			(at 0 0 180)
			(size 9.017 14.0208)
			(drill 3.0226
				(offset 0 2.499868)
			)
			(layers "*.Cu" "*.Mask")
			(remove_unused_layers no)
			(net "GND")
			(clearance -1.500378)
			(padstack
				(mode front_inner_back)
				(layer "Inner"
					(shape circle)
					(size 0 0)
					(clearance 0)
				)
				(layer "B.Cu"
					(shape oval)
					(size 9.017 14.0208)
					(offset 0 2.499868)
					(clearance -1.500378)
				)
			)
		)
	)
	(footprint ""
		(layer "F.Cu")
		(at 168.956736 -67.183)
		(property "Reference" "R5892"
			(at 0 0 0)
			(layer "F.SilkS")
			(hide yes)
			(effects
				(font
					(size 1.27 1.27)
				)
			)
		)
		(property "Value" ""
			(at 0 0 0)
			(layer "F.Fab")
			(effects
				(font
					(size 1.27 1.27)
				)
			)
		)
		(duplicate_pad_numbers_are_jumpers no)
		(fp_line
			(start -0.7874 -0.4064)
			(end 0.7874 -0.4064)
			(stroke
				(width 0.1524)
				(type default)
			)
			(layer "F.SilkS")
		)
		(fp_line
			(start -0.7874 0.4064)
			(end -0.7874 -0.4064)
			(stroke
				(width 0.1524)
				(type default)
			)
			(layer "F.SilkS")
		)
		(fp_line
			(start 0.7874 -0.4064)
			(end 0.7874 0.4064)
			(stroke
				(width 0.1524)
				(type default)
			)
			(layer "F.SilkS")
		)
		(fp_line
			(start 0.7874 0.4064)
			(end -0.7874 0.4064)
			(stroke
				(width 0.1524)
				(type default)
			)
			(layer "F.SilkS")
		)
		(fp_line
			(start -0.67945 -0.305054)
			(end -0.12065 -0.305054)
			(stroke
				(width 0.1)
				(type default)
			)
			(layer "F.Fab")
		)
		(fp_line
			(start -0.67945 0.3048)
			(end -0.67945 -0.305054)
			(stroke
				(width 0.1)
				(type default)
			)
			(layer "F.Fab")
		)
		(fp_line
			(start -0.12065 -0.305054)
			(end -0.12065 -0.2794)
			(stroke
				(width 0.1)
				(type default)
			)
			(layer "F.Fab")
		)
		(fp_line
			(start -0.12065 -0.2794)
			(end 0.12065 -0.2794)
			(stroke
				(width 0.1)
				(type default)
			)
			(layer "F.Fab")
		)
		(fp_line
			(start -0.12065 0.2794)
			(end -0.12065 0.3048)
			(stroke
				(width 0.1)
				(type default)
			)
			(layer "F.Fab")
		)
		(fp_line
			(start -0.12065 0.3048)
			(end -0.67945 0.3048)
			(stroke
				(width 0.1)
				(type default)
			)
			(layer "F.Fab")
		)
		(fp_line
			(start 0.120396 0.2794)
			(end -0.12065 0.2794)
			(stroke
				(width 0.1)
				(type default)
			)
			(layer "F.Fab")
		)
		(fp_line
			(start 0.120396 0.3048)
			(end 0.120396 0.2794)
			(stroke
				(width 0.1)
				(type default)
			)
			(layer "F.Fab")
		)
		(fp_line
			(start 0.12065 -0.3048)
			(end 0.67945 -0.3048)
			(stroke
				(width 0.1)
				(type default)
			)
			(layer "F.Fab")
		)
		(fp_line
			(start 0.12065 -0.2794)
			(end 0.12065 -0.3048)
			(stroke
				(width 0.1)
				(type default)
			)
			(layer "F.Fab")
		)
		(fp_line
			(start 0.67945 -0.3048)
			(end 0.67945 0.3048)
			(stroke
				(width 0.1)
				(type default)
			)
			(layer "F.Fab")
		)
		(fp_line
			(start 0.67945 0.3048)
			(end 0.120396 0.3048)
			(stroke
				(width 0.1)
				(type default)
			)
			(layer "F.Fab")
		)
		(pad "1" smd circle
			(at -0.40005 0)
			(size 0 0)
			(layers "F.Cu" "F.Mask" "F.Paste")
			(net "P52V_HS2_VCAP")
		)
		(pad "2" smd circle
			(at 0.40005 0)
			(size 0 0)
			(layers "F.Cu" "F.Mask" "F.Paste")
			(net "P52V_HS2_ADR1")
		)
	)
)
